(kicad_pcb
	(version 20241229)
	(generator "pcbnew")
	(generator_version "9.0")
	(general
		(thickness 1.711)
		(legacy_teardrops no)
	)
	(paper "A4")
	(title_block
		(title "Antmicro Baseboard for Jetson AGX Thor")
		(date "2026-02-18")
		(rev "1.1.0")
		(company "Antmicro Ltd")
		(comment 1 "www.antmicro.com")
		(comment 9 "footprints 658-662 of 1170")
	)
	(layers
		(0 "F.Cu" signal)
		(4 "In1.Cu" signal)
		(6 "In2.Cu" signal)
		(8 "In3.Cu" signal)
		(10 "In4.Cu" jumper)
		(12 "In5.Cu" signal)
		(14 "In6.Cu" signal)
		(16 "In7.Cu" signal)
		(18 "In8.Cu" signal)
		(2 "B.Cu" signal)
		(9 "F.Adhes" user "F.Adhesive")
		(11 "B.Adhes" user "B.Adhesive")
		(13 "F.Paste" user)
		(15 "B.Paste" user)
		(5 "F.SilkS" user "F.Silkscreen")
		(7 "B.SilkS" user "B.Silkscreen")
		(1 "F.Mask" user)
		(3 "B.Mask" user)
		(17 "Dwgs.User" user "User.Drawings")
		(19 "Cmts.User" user "User.Comments")
		(21 "Eco1.User" user "User.Eco1")
		(23 "Eco2.User" user "User.Eco2")
		(25 "Edge.Cuts" user)
		(27 "Margin" user)
		(31 "F.CrtYd" user "F.Courtyard")
		(29 "B.CrtYd" user "B.Courtyard")
		(35 "F.Fab" user)
		(33 "B.Fab" user)
	)
	(footprint "antmicro-footprints:C_0402_1005Metric"
		(layer "B.Cu")
		(at 115.82 70.6 180)
		(descr "Capacitor SMD 0402")
		(tags "capacitor SMD 0402")
		(property "Reference" "C14"
			(at -1.48 -1.5 0)
			(layer "B.SilkS")
			(effects
				(font
					(size 0.7 0.7)
					(thickness 0.15)
				)
				(justify left bottom mirror)
			)
		)
		(property "Value" "C_10u_0402"
			(at -1.022927 -2.155213 0)
			(layer "B.Fab")
			(effects
				(font
					(size 0.7 0.7)
					(thickness 0.15)
				)
				(justify left bottom mirror)
			)
		)
		(property "Datasheet" "https://www.yageo.com/en/Chart/Download/pdf/CC0402MRX5R5BB106"
			(at 0 0 0)
			(layer "B.Fab")
			(hide yes)
			(effects
				(font
					(size 1.27 1.27)
					(thickness 0.15)
				)
				(justify mirror)
			)
		)
		(property "Description" "SMD Multilayer Ceramic Capacitor, 10 µF, 6.3 V, 0402 [1005 Metric], ± 20%, X5R, CC Series"
			(at 0 0 0)
			(layer "B.Fab")
			(hide yes)
			(effects
				(font
					(size 1.27 1.27)
					(thickness 0.15)
				)
				(justify mirror)
			)
		)
		(property "MPN" "CC0402MRX5R5BB106"
			(at 0 0 180)
			(unlocked yes)
			(layer "B.Fab")
			(hide yes)
			(effects
				(font
					(size 1 1)
					(thickness 0.15)
				)
				(justify mirror)
			)
		)
		(property "Manufacturer" "YAGEO"
			(at 0 0 180)
			(unlocked yes)
			(layer "B.Fab")
			(hide yes)
			(effects
				(font
					(size 1 1)
					(thickness 0.15)
				)
				(justify mirror)
			)
		)
		(property "License" "Apache-2.0"
			(at 0 0 180)
			(unlocked yes)
			(layer "B.Fab")
			(hide yes)
			(effects
				(font
					(size 1 1)
					(thickness 0.15)
				)
				(justify mirror)
			)
		)
		(property "Author" "Antmicro"
			(at 0 0 180)
			(unlocked yes)
			(layer "B.Fab")
			(hide yes)
			(effects
				(font
					(size 1 1)
					(thickness 0.15)
				)
				(justify mirror)
			)
		)
		(property "Val" "10u"
			(at 0 0 180)
			(unlocked yes)
			(layer "B.Fab")
			(hide yes)
			(effects
				(font
					(size 1 1)
					(thickness 0.15)
				)
				(justify mirror)
			)
		)
		(property "Voltage" ""
			(at 0 0 180)
			(unlocked yes)
			(layer "B.Fab")
			(hide yes)
			(effects
				(font
					(size 1 1)
					(thickness 0.15)
				)
				(justify mirror)
			)
		)
		(property "Dielectric" "template_dielectric"
			(at 0 0 180)
			(unlocked yes)
			(layer "B.Fab")
			(hide yes)
			(effects
				(font
					(size 1 1)
					(thickness 0.15)
				)
				(justify mirror)
			)
		)
		(sheetname "/SoM_Power/")
		(sheetfile "som_power.kicad_sch")
		(attr smd)
		(fp_rect
			(start -0.925 0.47)
			(end 0.925 -0.47)
			(stroke
				(width 0.05)
				(type default)
			)
			(fill no)
			(layer "B.CrtYd")
		)
		(fp_line
			(start 0.504 0.25)
			(end 0.504 -0.248)
			(stroke
				(width 0.15)
				(type solid)
			)
			(layer "B.Fab")
		)
		(fp_line
			(start 0.504 -0.248)
			(end -0.494 -0.248)
			(stroke
				(width 0.15)
				(type solid)
			)
			(layer "B.Fab")
		)
		(fp_line
			(start -0.494 0.25)
			(end 0.504 0.25)
			(stroke
				(width 0.15)
				(type solid)
			)
			(layer "B.Fab")
		)
		(fp_line
			(start -0.494 -0.248)
			(end -0.494 0.25)
			(stroke
				(width 0.15)
				(type solid)
			)
			(layer "B.Fab")
		)
		(fp_text user "License: Apache-2.0"
			(at -0.939 -5.799 0)
			(layer "B.Fab")
			(effects
				(font
					(size 0.7 0.7)
					(thickness 0.15)
				)
				(justify left bottom mirror)
			)
		)
		(fp_text user "Author: Antmicro"
			(at -0.939 -3.399 0)
			(layer "B.Fab")
			(effects
				(font
					(size 0.7 0.7)
					(thickness 0.15)
				)
				(justify left bottom mirror)
			)
		)
		(fp_text user "${REFERENCE}"
			(at -0.939 -4.599 0)
			(layer "B.Fab")
			(effects
				(font
					(size 0.7 0.7)
					(thickness 0.15)
				)
				(justify left bottom mirror)
			)
		)
		(pad "1" smd roundrect
			(at -0.48 0 180)
			(size 0.59 0.64)
			(layers "B.Cu" "B.Mask" "B.Paste")
			(roundrect_rratio 0.25)
			(net 1 "GND")
			(pintype "passive")
		)
		(pad "2" smd roundrect
			(at 0.48 0 180)
			(size 0.59 0.64)
			(layers "B.Cu" "B.Mask" "B.Paste")
			(roundrect_rratio 0.25)
			(net 213 "+5V_SOM")
			(pintype "passive")
		)
	)
	(footprint "antmicro-footprints:R_0402_1005Metric"
		(layer "B.Cu")
		(at 65 63.58 90)
		(descr "Resistor SMD 0402")
		(tags "resistor SMD 0402")
		(property "Reference" "R161"
			(at 0.78 -0.4 90)
			(layer "B.SilkS")
			(effects
				(font
					(size 0.7 0.7)
					(thickness 0.15)
				)
				(justify right top mirror)
			)
		)
		(property "Value" "R_0R_0402"
			(at -1.011843 -1.772046 90)
			(layer "B.Fab")
			(effects
				(font
					(size 0.7 0.7)
					(thickness 0.15)
				)
				(justify right top mirror)
			)
		)
		(property "Datasheet" "https://industrial.panasonic.com/cdbs/www-data/pdf/RDA0000/AOA0000C301.pdf"
			(at 0 0 90)
			(layer "B.Fab")
			(hide yes)
			(effects
				(font
					(size 1.27 1.27)
					(thickness 0.15)
				)
				(justify mirror)
			)
		)
		(property "Description" "SMD Chip Resistor, Jumper, 0 ohm, 100 mW, 0402 [1005 Metric], Thick Film, General Purpose"
			(at 0 0 90)
			(layer "B.Fab")
			(hide yes)
			(effects
				(font
					(size 1.27 1.27)
					(thickness 0.15)
				)
				(justify mirror)
			)
		)
		(property "Manufacturer" "Panasonic"
			(at 0 0 270)
			(unlocked yes)
			(layer "B.Fab")
			(hide yes)
			(effects
				(font
					(size 1 1)
					(thickness 0.15)
				)
				(justify mirror)
			)
		)
		(property "MPN" "ERJ2GE0R00X"
			(at 0 0 270)
			(unlocked yes)
			(layer "B.Fab")
			(hide yes)
			(effects
				(font
					(size 1 1)
					(thickness 0.15)
				)
				(justify mirror)
			)
		)
		(property "Val" "0R"
			(at 0 0 270)
			(unlocked yes)
			(layer "B.Fab")
			(hide yes)
			(effects
				(font
					(size 1 1)
					(thickness 0.15)
				)
				(justify mirror)
			)
		)
		(property "License" "Apache-2.0"
			(at 0 0 270)
			(unlocked yes)
			(layer "B.Fab")
			(hide yes)
			(effects
				(font
					(size 1 1)
					(thickness 0.15)
				)
				(justify mirror)
			)
		)
		(property "Author" "Antmicro"
			(at 0 0 270)
			(unlocked yes)
			(layer "B.Fab")
			(hide yes)
			(effects
				(font
					(size 1 1)
					(thickness 0.15)
				)
				(justify mirror)
			)
		)
		(property "Tolerance" "~"
			(at 0 0 270)
			(unlocked yes)
			(layer "B.Fab")
			(hide yes)
			(effects
				(font
					(size 1 1)
					(thickness 0.15)
				)
				(justify mirror)
			)
		)
		(property "Current" "1A"
			(at 0 0 270)
			(unlocked yes)
			(layer "B.Fab")
			(hide yes)
			(effects
				(font
					(size 1 1)
					(thickness 0.15)
				)
				(justify mirror)
			)
		)
		(sheetname "/CSI/")
		(sheetfile "csi.kicad_sch")
		(attr smd exclude_from_pos_files exclude_from_bom dnp)
		(fp_poly
			(pts
				(xy -0.925 0.47) (xy -0.925 -0.47) (xy 0.925 -0.47) (xy 0.925 0.47)
			)
			(stroke
				(width 0.05)
				(type default)
			)
			(fill no)
			(layer "B.CrtYd")
		)
		(fp_poly
			(pts
				(xy -0.5 0.25) (xy -0.5 -0.25) (xy 0.5 -0.25) (xy 0.5 0.25)
			)
			(stroke
				(width 0.15)
				(type solid)
			)
			(fill no)
			(layer "B.Fab")
		)
		(fp_text user "Author: Antmicro"
			(at -0.95 -4.169 90)
			(layer "B.Fab")
			(effects
				(font
					(size 0.7 0.7)
					(thickness 0.15)
				)
				(justify right top mirror)
			)
		)
		(fp_text user "License: Apache-2.0"
			(at -0.949999 -5.169 90)
			(layer "B.Fab")
			(effects
				(font
					(size 0.7 0.7)
					(thickness 0.15)
				)
				(justify right top mirror)
			)
		)
		(fp_text user "${REFERENCE}"
			(at -0.95 -3.168 90)
			(layer "B.Fab")
			(effects
				(font
					(size 0.7 0.7)
					(thickness 0.15)
				)
				(justify right top mirror)
			)
		)
		(pad "1" smd roundrect
			(at -0.48 0 90)
			(size 0.59 0.64)
			(layers "B.Cu" "B.Mask" "B.Paste")
			(roundrect_rratio 0.25)
			(net 979 "/CSI/CSIA_I2C_VCC")
			(pintype "passive")
		)
		(pad "2" smd roundrect
			(at 0.48 0 90)
			(size 0.59 0.64)
			(layers "B.Cu" "B.Mask" "B.Paste")
			(roundrect_rratio 0.25)
			(net 11 "+1V8")
			(pintype "passive")
		)
	)
	(footprint "antmicro-footprints:R_0402_1005Metric"
		(layer "B.Cu")
		(at 216 89.2 180)
		(descr "Resistor SMD 0402")
		(tags "resistor SMD 0402")
		(property "Reference" "R141"
			(at -7.6 -2.4 0)
			(layer "B.SilkS")
			(effects
				(font
					(size 0.7 0.7)
					(thickness 0.15)
				)
				(justify left bottom mirror)
			)
		)
		(property "Value" "R_1k_0402"
			(at -1.011843 -1.772047 0)
			(layer "B.Fab")
			(effects
				(font
					(size 0.7 0.7)
					(thickness 0.15)
				)
				(justify left bottom mirror)
			)
		)
		(property "Datasheet" "https://www.bourns.com/docs/product-datasheets/cr.pdf"
			(at 0 0 0)
			(layer "B.Fab")
			(hide yes)
			(effects
				(font
					(size 1.27 1.27)
					(thickness 0.15)
				)
				(justify mirror)
			)
		)
		(property "Description" "SMD Chip Resistor, 1 kohm, ± 1%, 63 mW, 0402 [1005 Metric], Thick Film, General Purpose"
			(at 0 0 0)
			(layer "B.Fab")
			(hide yes)
			(effects
				(font
					(size 1.27 1.27)
					(thickness 0.15)
				)
				(justify mirror)
			)
		)
		(property "Manufacturer" "Bourns"
			(at 0 0 0)
			(unlocked yes)
			(layer "B.Fab")
			(hide yes)
			(effects
				(font
					(size 1 1)
					(thickness 0.15)
				)
				(justify mirror)
			)
		)
		(property "MPN" "CR0402-FX-1001GLF"
			(at 0 0 0)
			(unlocked yes)
			(layer "B.Fab")
			(hide yes)
			(effects
				(font
					(size 1 1)
					(thickness 0.15)
				)
				(justify mirror)
			)
		)
		(property "Val" "1k"
			(at 0 0 0)
			(unlocked yes)
			(layer "B.Fab")
			(hide yes)
			(effects
				(font
					(size 1 1)
					(thickness 0.15)
				)
				(justify mirror)
			)
		)
		(property "License" "Apache-2.0"
			(at 0 0 0)
			(unlocked yes)
			(layer "B.Fab")
			(hide yes)
			(effects
				(font
					(size 1 1)
					(thickness 0.15)
				)
				(justify mirror)
			)
		)
		(property "Author" "Antmicro"
			(at 0 0 0)
			(unlocked yes)
			(layer "B.Fab")
			(hide yes)
			(effects
				(font
					(size 1 1)
					(thickness 0.15)
				)
				(justify mirror)
			)
		)
		(property "Tolerance" "1%"
			(at 0 0 0)
			(unlocked yes)
			(layer "B.Fab")
			(hide yes)
			(effects
				(font
					(size 1 1)
					(thickness 0.15)
				)
				(justify mirror)
			)
		)
		(sheetname "/USB DP Alt mode/")
		(sheetfile "usb_dp.kicad_sch")
		(attr smd)
		(fp_rect
			(start -0.925 0.47)
			(end 0.925 -0.47)
			(stroke
				(width 0.05)
				(type default)
			)
			(fill no)
			(layer "B.CrtYd")
		)
		(fp_rect
			(start -0.5 0.25)
			(end 0.5 -0.25)
			(stroke
				(width 0.15)
				(type solid)
			)
			(fill no)
			(layer "B.Fab")
		)
		(fp_text user "Author: Antmicro"
			(at -0.95 -4.169 0)
			(layer "B.Fab")
			(effects
				(font
					(size 0.7 0.7)
					(thickness 0.15)
				)
				(justify left bottom mirror)
			)
		)
		(fp_text user "License: Apache-2.0"
			(at -0.95 -5.169 0)
			(layer "B.Fab")
			(effects
				(font
					(size 0.7 0.7)
					(thickness 0.15)
				)
				(justify left bottom mirror)
			)
		)
		(fp_text user "${REFERENCE}"
			(at -0.95 -3.168 0)
			(layer "B.Fab")
			(effects
				(font
					(size 0.7 0.7)
					(thickness 0.15)
				)
				(justify left bottom mirror)
			)
		)
		(pad "1" smd roundrect
			(at -0.48 0 180)
			(size 0.59 0.64)
			(layers "B.Cu" "B.Mask" "B.Paste")
			(roundrect_rratio 0.25)
			(net 969 "/USB DP Alt mode/USBC1_EQ1")
			(pintype "passive")
		)
		(pad "2" smd roundrect
			(at 0.48 0 180)
			(size 0.59 0.64)
			(layers "B.Cu" "B.Mask" "B.Paste")
			(roundrect_rratio 0.25)
			(net 1 "GND")
			(pintype "passive")
		)
	)
	(footprint "antmicro-footprints:R_0402_1005Metric"
		(layer "B.Cu")
		(at 218.714999 86.718 -90)
		(descr "Resistor SMD 0402")
		(tags "resistor SMD 0402")
		(property "Reference" "R132"
			(at -0.918 -2.485001 90)
			(layer "B.SilkS")
			(effects
				(font
					(size 0.7 0.7)
					(thickness 0.15)
				)
				(justify left bottom mirror)
			)
		)
		(property "Value" "R_1k_0402"
			(at -1.011843 -1.772046 90)
			(layer "B.Fab")
			(effects
				(font
					(size 0.7 0.7)
					(thickness 0.15)
				)
				(justify left bottom mirror)
			)
		)
		(property "Datasheet" "https://www.bourns.com/docs/product-datasheets/cr.pdf"
			(at 0 0 90)
			(layer "B.Fab")
			(hide yes)
			(effects
				(font
					(size 1.27 1.27)
					(thickness 0.15)
				)
				(justify mirror)
			)
		)
		(property "Description" "SMD Chip Resistor, 1 kohm, ± 1%, 63 mW, 0402 [1005 Metric], Thick Film, General Purpose"
			(at 0 0 90)
			(layer "B.Fab")
			(hide yes)
			(effects
				(font
					(size 1.27 1.27)
					(thickness 0.15)
				)
				(justify mirror)
			)
		)
		(property "Manufacturer" "Bourns"
			(at 0 0 90)
			(unlocked yes)
			(layer "B.Fab")
			(hide yes)
			(effects
				(font
					(size 1 1)
					(thickness 0.15)
				)
				(justify mirror)
			)
		)
		(property "MPN" "CR0402-FX-1001GLF"
			(at 0 0 90)
			(unlocked yes)
			(layer "B.Fab")
			(hide yes)
			(effects
				(font
					(size 1 1)
					(thickness 0.15)
				)
				(justify mirror)
			)
		)
		(property "Val" "1k"
			(at 0 0 90)
			(unlocked yes)
			(layer "B.Fab")
			(hide yes)
			(effects
				(font
					(size 1 1)
					(thickness 0.15)
				)
				(justify mirror)
			)
		)
		(property "License" "Apache-2.0"
			(at 0 0 90)
			(unlocked yes)
			(layer "B.Fab")
			(hide yes)
			(effects
				(font
					(size 1 1)
					(thickness 0.15)
				)
				(justify mirror)
			)
		)
		(property "Author" "Antmicro"
			(at 0 0 90)
			(unlocked yes)
			(layer "B.Fab")
			(hide yes)
			(effects
				(font
					(size 1 1)
					(thickness 0.15)
				)
				(justify mirror)
			)
		)
		(property "Tolerance" "1%"
			(at 0 0 90)
			(unlocked yes)
			(layer "B.Fab")
			(hide yes)
			(effects
				(font
					(size 1 1)
					(thickness 0.15)
				)
				(justify mirror)
			)
		)
		(sheetname "/USB DP Alt mode/")
		(sheetfile "usb_dp.kicad_sch")
		(attr smd exclude_from_pos_files exclude_from_bom dnp)
		(fp_poly
			(pts
				(xy -0.925 0.47) (xy 0.925 0.47) (xy 0.925 -0.47) (xy -0.925 -0.47)
			)
			(stroke
				(width 0.05)
				(type default)
			)
			(fill no)
			(layer "B.CrtYd")
		)
		(fp_poly
			(pts
				(xy -0.5 0.25) (xy 0.5 0.25) (xy 0.5 -0.25) (xy -0.5 -0.25)
			)
			(stroke
				(width 0.15)
				(type solid)
			)
			(fill no)
			(layer "B.Fab")
		)
		(fp_text user "${REFERENCE}"
			(at -0.95 -3.168 90)
			(layer "B.Fab")
			(effects
				(font
					(size 0.7 0.7)
					(thickness 0.15)
				)
				(justify left bottom mirror)
			)
		)
		(fp_text user "Author: Antmicro"
			(at -0.95 -4.169 90)
			(layer "B.Fab")
			(effects
				(font
					(size 0.7 0.7)
					(thickness 0.15)
				)
				(justify left bottom mirror)
			)
		)
		(fp_text user "License: Apache-2.0"
			(at -0.949999 -5.169 90)
			(layer "B.Fab")
			(effects
				(font
					(size 0.7 0.7)
					(thickness 0.15)
				)
				(justify left bottom mirror)
			)
		)
		(pad "1" smd roundrect
			(at -0.48 0 270)
			(size 0.59 0.64)
			(layers "B.Cu" "B.Mask" "B.Paste")
			(roundrect_rratio 0.25)
			(net 965 "/USB DP Alt mode/USBC1_SSEQ1")
			(pintype "passive")
		)
		(pad "2" smd roundrect
			(at 0.48 0 270)
			(size 0.59 0.64)
			(layers "B.Cu" "B.Mask" "B.Paste")
			(roundrect_rratio 0.25)
			(net 2 "+3V3")
			(pintype "passive")
		)
	)
	(footprint "antmicro-footprints:R_0402_1005Metric"
		(layer "B.Cu")
		(at 67.16 63.58 90)
		(descr "Resistor SMD 0402")
		(tags "resistor SMD 0402")
		(property "Reference" "R169"
			(at 0.78 -0.31 90)
			(layer "B.SilkS")
			(effects
				(font
					(size 0.7 0.7)
					(thickness 0.15)
				)
				(justify right top mirror)
			)
		)
		(property "Value" "R_0R_0402"
			(at -1.011843 -1.772046 90)
			(layer "B.Fab")
			(effects
				(font
					(size 0.7 0.7)
					(thickness 0.15)
				)
				(justify right top mirror)
			)
		)
		(property "Datasheet" "https://industrial.panasonic.com/cdbs/www-data/pdf/RDA0000/AOA0000C301.pdf"
			(at 0 0 90)
			(layer "B.Fab")
			(hide yes)
			(effects
				(font
					(size 1.27 1.27)
					(thickness 0.15)
				)
				(justify mirror)
			)
		)
		(property "Description" "SMD Chip Resistor, Jumper, 0 ohm, 100 mW, 0402 [1005 Metric], Thick Film, General Purpose"
			(at 0 0 90)
			(layer "B.Fab")
			(hide yes)
			(effects
				(font
					(size 1.27 1.27)
					(thickness 0.15)
				)
				(justify mirror)
			)
		)
		(property "Manufacturer" "Panasonic"
			(at 0 0 270)
			(unlocked yes)
			(layer "B.Fab")
			(hide yes)
			(effects
				(font
					(size 1 1)
					(thickness 0.15)
				)
				(justify mirror)
			)
		)
		(property "MPN" "ERJ2GE0R00X"
			(at 0 0 270)
			(unlocked yes)
			(layer "B.Fab")
			(hide yes)
			(effects
				(font
					(size 1 1)
					(thickness 0.15)
				)
				(justify mirror)
			)
		)
		(property "Val" "0R"
			(at 0 0 270)
			(unlocked yes)
			(layer "B.Fab")
			(hide yes)
			(effects
				(font
					(size 1 1)
					(thickness 0.15)
				)
				(justify mirror)
			)
		)
		(property "License" "Apache-2.0"
			(at 0 0 270)
			(unlocked yes)
			(layer "B.Fab")
			(hide yes)
			(effects
				(font
					(size 1 1)
					(thickness 0.15)
				)
				(justify mirror)
			)
		)
		(property "Author" "Antmicro"
			(at 0 0 270)
			(unlocked yes)
			(layer "B.Fab")
			(hide yes)
			(effects
				(font
					(size 1 1)
					(thickness 0.15)
				)
				(justify mirror)
			)
		)
		(property "Tolerance" "~"
			(at 0 0 270)
			(unlocked yes)
			(layer "B.Fab")
			(hide yes)
			(effects
				(font
					(size 1 1)
					(thickness 0.15)
				)
				(justify mirror)
			)
		)
		(property "Current" "1A"
			(at 0 0 270)
			(unlocked yes)
			(layer "B.Fab")
			(hide yes)
			(effects
				(font
					(size 1 1)
					(thickness 0.15)
				)
				(justify mirror)
			)
		)
		(sheetname "/CSI/")
		(sheetfile "csi.kicad_sch")
		(attr smd)
		(fp_poly
			(pts
				(xy -0.925 0.47) (xy -0.925 -0.47) (xy 0.925 -0.47) (xy 0.925 0.47)
			)
			(stroke
				(width 0.05)
				(type default)
			)
			(fill no)
			(layer "B.CrtYd")
		)
		(fp_poly
			(pts
				(xy -0.5 0.25) (xy -0.5 -0.25) (xy 0.5 -0.25) (xy 0.5 0.25)
			)
			(stroke
				(width 0.15)
				(type solid)
			)
			(fill no)
			(layer "B.Fab")
		)
		(fp_text user "License: Apache-2.0"
			(at -0.949999 -5.169 90)
			(layer "B.Fab")
			(effects
				(font
					(size 0.7 0.7)
					(thickness 0.15)
				)
				(justify right top mirror)
			)
		)
		(fp_text user "Author: Antmicro"
			(at -0.95 -4.169 90)
			(layer "B.Fab")
			(effects
				(font
					(size 0.7 0.7)
					(thickness 0.15)
				)
				(justify right top mirror)
			)
		)
		(fp_text user "${REFERENCE}"
			(at -0.95 -3.168 90)
			(layer "B.Fab")
			(effects
				(font
					(size 0.7 0.7)
					(thickness 0.15)
				)
				(justify right top mirror)
			)
		)
		(pad "1" smd roundrect
			(at -0.48 0 90)
			(size 0.59 0.64)
			(layers "B.Cu" "B.Mask" "B.Paste")
			(roundrect_rratio 0.25)
			(net 990 "/CSI/CSIB_I2C_VCC")
			(pintype "passive")
		)
		(pad "2" smd roundrect
			(at 0.48 0 90)
			(size 0.59 0.64)
			(layers "B.Cu" "B.Mask" "B.Paste")
			(roundrect_rratio 0.25)
			(net 2 "+3V3")
			(pintype "passive")
		)
	)
)
